(kicad_pcb
	(version 20260206)
	(generator "pcbnew")
	(generator_version "10.0")
	(general
		(thickness 1.6)
		(legacy_teardrops no)
	)
	(paper "A4")
	(title_block
		(title "04192023_DAF0TMB3IC0_F0TG_MB_C_brd_V02_OCP.brd")
		(comment 1 "Grand Teton / footprints 7088-7095 of 8354")
	)
	(layers
		(0 "F.Cu" signal "TOP")
		(4 "In1.Cu" signal "GND")
		(6 "In2.Cu" signal "IN1")
		(8 "In3.Cu" signal "GND1")
		(10 "In4.Cu" signal "IN2")
		(12 "In5.Cu" signal "GND2")
		(14 "In6.Cu" signal "IN3")
		(16 "In7.Cu" signal "GND3")
		(18 "In8.Cu" signal "VCC")
		(20 "In9.Cu" signal "VCC1")
		(22 "In10.Cu" signal "GND4")
		(24 "In11.Cu" signal "IN4")
		(26 "In12.Cu" signal "GND5")
		(28 "In13.Cu" signal "IN5")
		(30 "In14.Cu" signal "GND6")
		(32 "In15.Cu" signal "IN6")
		(34 "In16.Cu" signal "GND7")
		(2 "B.Cu" signal "BOTTOM")
		(9 "F.Adhes" user "F.Adhesive")
		(11 "B.Adhes" user "B.Adhesive")
		(13 "F.Paste" user "Package Geometry/Pastemask Top")
		(15 "B.Paste" user "Package Geometry/Pastemask Bottom")
		(5 "F.SilkS" user "Ref Des/Silkscreen Top")
		(7 "B.SilkS" user "Ref Des/Silkscreen Bottom")
		(1 "F.Mask" user "Board Geometry/Soldermask Top")
		(3 "B.Mask" user "Board Geometry/Soldermask Bottom")
		(17 "Dwgs.User" user "User.Drawings")
		(19 "Cmts.User" user "User.Comments")
		(21 "Eco1.User" user "User.Eco1")
		(23 "Eco2.User" user "User.Eco2")
		(25 "Edge.Cuts" user "Board Geometry/Outline")
		(27 "Margin" user)
		(31 "F.CrtYd" user "Package Geometry/Place Bound Top")
		(29 "B.CrtYd" user "Package Geometry/Place Bound Bottom")
		(35 "F.Fab" user "Ref Des/Assembly Top")
		(33 "B.Fab" user "Ref Des/Assembly Bottom")
	)
	(footprint ""
		(layer "B.Cu")
		(at 416.84067 -162.70859 90)
		(property "Reference" "PR364"
			(at 0 0 90)
			(layer "B.SilkS")
			(hide yes)
			(effects
				(font
					(size 1.27 1.27)
				)
				(justify mirror)
			)
		)
		(property "Value" ""
			(at 0 0 90)
			(layer "B.Fab")
			(effects
				(font
					(size 1.27 1.27)
				)
				(justify mirror)
			)
		)
		(duplicate_pad_numbers_are_jumpers no)
		(fp_line
			(start 0.7874 -0.4064)
			(end -0.7874 -0.4064)
			(stroke
				(width 0.1524)
				(type default)
			)
			(layer "B.SilkS")
		)
		(fp_line
			(start -0.7874 -0.4064)
			(end -0.7874 0.4064)
			(stroke
				(width 0.1524)
				(type default)
			)
			(layer "B.SilkS")
		)
		(fp_line
			(start 0.7874 0.4064)
			(end 0.7874 -0.4064)
			(stroke
				(width 0.1524)
				(type default)
			)
			(layer "B.SilkS")
		)
		(fp_line
			(start -0.7874 0.4064)
			(end 0.7874 0.4064)
			(stroke
				(width 0.1524)
				(type default)
			)
			(layer "B.SilkS")
		)
		(fp_line
			(start 0.67945 -0.305054)
			(end 0.12065 -0.305054)
			(stroke
				(width 0.1)
				(type default)
			)
			(layer "B.Fab")
		)
		(fp_line
			(start 0.12065 -0.305054)
			(end 0.12065 -0.2794)
			(stroke
				(width 0.1)
				(type default)
			)
			(layer "B.Fab")
		)
		(fp_line
			(start -0.12065 -0.3048)
			(end -0.67945 -0.3048)
			(stroke
				(width 0.1)
				(type default)
			)
			(layer "B.Fab")
		)
		(fp_line
			(start -0.67945 -0.3048)
			(end -0.67945 0.3048)
			(stroke
				(width 0.1)
				(type default)
			)
			(layer "B.Fab")
		)
		(fp_line
			(start 0.12065 -0.2794)
			(end -0.12065 -0.2794)
			(stroke
				(width 0.1)
				(type default)
			)
			(layer "B.Fab")
		)
		(fp_line
			(start -0.12065 -0.2794)
			(end -0.12065 -0.3048)
			(stroke
				(width 0.1)
				(type default)
			)
			(layer "B.Fab")
		)
		(fp_line
			(start 0.12065 0.2794)
			(end 0.12065 0.3048)
			(stroke
				(width 0.1)
				(type default)
			)
			(layer "B.Fab")
		)
		(fp_line
			(start -0.120396 0.2794)
			(end 0.12065 0.2794)
			(stroke
				(width 0.1)
				(type default)
			)
			(layer "B.Fab")
		)
		(fp_line
			(start 0.67945 0.3048)
			(end 0.67945 -0.305054)
			(stroke
				(width 0.1)
				(type default)
			)
			(layer "B.Fab")
		)
		(fp_line
			(start 0.12065 0.3048)
			(end 0.67945 0.3048)
			(stroke
				(width 0.1)
				(type default)
			)
			(layer "B.Fab")
		)
		(fp_line
			(start -0.120396 0.3048)
			(end -0.120396 0.2794)
			(stroke
				(width 0.1)
				(type default)
			)
			(layer "B.Fab")
		)
		(fp_line
			(start -0.67945 0.3048)
			(end -0.120396 0.3048)
			(stroke
				(width 0.1)
				(type default)
			)
			(layer "B.Fab")
		)
		(pad "1" smd circle
			(at 0.40005 0 270)
			(size 0 0)
			(layers "B.Cu" "B.Mask" "B.Paste")
			(net "PVDDCR_CPU0_P0_PVCC")
		)
		(pad "2" smd circle
			(at -0.40005 0 270)
			(size 0 0)
			(layers "B.Cu" "B.Mask" "B.Paste")
			(net "PVDDCR_SOC_P0_VCC3")
		)
	)
	(footprint ""
		(layer "B.Cu")
		(at 338.995766 -416.899344 90)
		(property "Reference" "C6556"
			(at 0 0 90)
			(layer "B.SilkS")
			(hide yes)
			(effects
				(font
					(size 1.27 1.27)
				)
				(justify mirror)
			)
		)
		(property "Value" ""
			(at 0 0 90)
			(layer "B.Fab")
			(effects
				(font
					(size 1.27 1.27)
				)
				(justify mirror)
			)
		)
		(duplicate_pad_numbers_are_jumpers no)
		(fp_line
			(start 0.299974 -0.150114)
			(end -0.299974 -0.150114)
			(stroke
				(width 0.1)
				(type default)
			)
			(layer "B.Fab")
		)
		(fp_line
			(start -0.299974 -0.150114)
			(end -0.299974 0.150114)
			(stroke
				(width 0.1)
				(type default)
			)
			(layer "B.Fab")
		)
		(fp_line
			(start 0.299974 0.150114)
			(end 0.299974 -0.150114)
			(stroke
				(width 0.1)
				(type default)
			)
			(layer "B.Fab")
		)
		(fp_line
			(start -0.299974 0.150114)
			(end 0.299974 0.150114)
			(stroke
				(width 0.1)
				(type default)
			)
			(layer "B.Fab")
		)
		(pad "1" smd rect
			(at 0.2667 0 270)
			(size 0.3048 0.381)
			(layers "B.Cu" "B.Mask" "B.Paste")
			(net "P5E_CPU0_P1_TX_BUF_C_DN<11>")
		)
		(pad "2" smd rect
			(at -0.2667 0 270)
			(size 0.3048 0.381)
			(layers "B.Cu" "B.Mask" "B.Paste")
			(net "P5E_CPU0_P1_TX_BUF_DN<11>")
		)
	)
	(footprint ""
		(layer "B.Cu")
		(at 59.233562 -190.64732 -90)
		(property "Reference" "R520"
			(at 0 0 90)
			(layer "B.SilkS")
			(hide yes)
			(effects
				(font
					(size 1.27 1.27)
				)
				(justify mirror)
			)
		)
		(property "Value" ""
			(at 0 0 90)
			(layer "B.Fab")
			(effects
				(font
					(size 1.27 1.27)
				)
				(justify mirror)
			)
		)
		(duplicate_pad_numbers_are_jumpers no)
		(fp_line
			(start -0.7874 0.4064)
			(end 0.7874 0.4064)
			(stroke
				(width 0.1524)
				(type default)
			)
			(layer "B.SilkS")
		)
		(fp_line
			(start 0.7874 0.4064)
			(end 0.7874 -0.4064)
			(stroke
				(width 0.1524)
				(type default)
			)
			(layer "B.SilkS")
		)
		(fp_line
			(start -0.7874 -0.4064)
			(end -0.7874 0.4064)
			(stroke
				(width 0.1524)
				(type default)
			)
			(layer "B.SilkS")
		)
		(fp_line
			(start 0.7874 -0.4064)
			(end -0.7874 -0.4064)
			(stroke
				(width 0.1524)
				(type default)
			)
			(layer "B.SilkS")
		)
		(fp_line
			(start -0.67945 0.3048)
			(end -0.120396 0.3048)
			(stroke
				(width 0.1)
				(type default)
			)
			(layer "B.Fab")
		)
		(fp_line
			(start -0.120396 0.3048)
			(end -0.120396 0.2794)
			(stroke
				(width 0.1)
				(type default)
			)
			(layer "B.Fab")
		)
		(fp_line
			(start 0.12065 0.3048)
			(end 0.67945 0.3048)
			(stroke
				(width 0.1)
				(type default)
			)
			(layer "B.Fab")
		)
		(fp_line
			(start 0.67945 0.3048)
			(end 0.67945 -0.305054)
			(stroke
				(width 0.1)
				(type default)
			)
			(layer "B.Fab")
		)
		(fp_line
			(start -0.120396 0.2794)
			(end 0.12065 0.2794)
			(stroke
				(width 0.1)
				(type default)
			)
			(layer "B.Fab")
		)
		(fp_line
			(start 0.12065 0.2794)
			(end 0.12065 0.3048)
			(stroke
				(width 0.1)
				(type default)
			)
			(layer "B.Fab")
		)
		(fp_line
			(start -0.12065 -0.2794)
			(end -0.12065 -0.3048)
			(stroke
				(width 0.1)
				(type default)
			)
			(layer "B.Fab")
		)
		(fp_line
			(start 0.12065 -0.2794)
			(end -0.12065 -0.2794)
			(stroke
				(width 0.1)
				(type default)
			)
			(layer "B.Fab")
		)
		(fp_line
			(start -0.67945 -0.3048)
			(end -0.67945 0.3048)
			(stroke
				(width 0.1)
				(type default)
			)
			(layer "B.Fab")
		)
		(fp_line
			(start -0.12065 -0.3048)
			(end -0.67945 -0.3048)
			(stroke
				(width 0.1)
				(type default)
			)
			(layer "B.Fab")
		)
		(fp_line
			(start 0.12065 -0.305054)
			(end 0.12065 -0.2794)
			(stroke
				(width 0.1)
				(type default)
			)
			(layer "B.Fab")
		)
		(fp_line
			(start 0.67945 -0.305054)
			(end 0.12065 -0.305054)
			(stroke
				(width 0.1)
				(type default)
			)
			(layer "B.Fab")
		)
		(pad "1" smd circle
			(at 0.40005 0 90)
			(size 0 0)
			(layers "B.Cu" "B.Mask" "B.Paste")
			(net "CPU1_PROCHOT_N")
		)
		(pad "2" smd circle
			(at -0.40005 0 90)
			(size 0 0)
			(layers "B.Cu" "B.Mask" "B.Paste")
			(net "PVDD18_S5_P1")
		)
	)
	(footprint ""
		(layer "B.Cu")
		(at 167.285162 -347.600016 90)
		(property "Reference" "R8011"
			(at 0 0 90)
			(layer "B.SilkS")
			(hide yes)
			(effects
				(font
					(size 1.27 1.27)
				)
				(justify mirror)
			)
		)
		(property "Value" ""
			(at 0 0 90)
			(layer "B.Fab")
			(effects
				(font
					(size 1.27 1.27)
				)
				(justify mirror)
			)
		)
		(duplicate_pad_numbers_are_jumpers no)
		(fp_line
			(start 0.7874 -0.4064)
			(end -0.7874 -0.4064)
			(stroke
				(width 0.1524)
				(type default)
			)
			(layer "B.SilkS")
		)
		(fp_line
			(start -0.7874 -0.4064)
			(end -0.7874 0.4064)
			(stroke
				(width 0.1524)
				(type default)
			)
			(layer "B.SilkS")
		)
		(fp_line
			(start 0.7874 0.4064)
			(end 0.7874 -0.4064)
			(stroke
				(width 0.1524)
				(type default)
			)
			(layer "B.SilkS")
		)
		(fp_line
			(start -0.7874 0.4064)
			(end 0.7874 0.4064)
			(stroke
				(width 0.1524)
				(type default)
			)
			(layer "B.SilkS")
		)
		(fp_line
			(start 0.67945 -0.305054)
			(end 0.12065 -0.305054)
			(stroke
				(width 0.1)
				(type default)
			)
			(layer "B.Fab")
		)
		(fp_line
			(start 0.12065 -0.305054)
			(end 0.12065 -0.2794)
			(stroke
				(width 0.1)
				(type default)
			)
			(layer "B.Fab")
		)
		(fp_line
			(start -0.12065 -0.3048)
			(end -0.67945 -0.3048)
			(stroke
				(width 0.1)
				(type default)
			)
			(layer "B.Fab")
		)
		(fp_line
			(start -0.67945 -0.3048)
			(end -0.67945 0.3048)
			(stroke
				(width 0.1)
				(type default)
			)
			(layer "B.Fab")
		)
		(fp_line
			(start 0.12065 -0.2794)
			(end -0.12065 -0.2794)
			(stroke
				(width 0.1)
				(type default)
			)
			(layer "B.Fab")
		)
		(fp_line
			(start -0.12065 -0.2794)
			(end -0.12065 -0.3048)
			(stroke
				(width 0.1)
				(type default)
			)
			(layer "B.Fab")
		)
		(fp_line
			(start 0.12065 0.2794)
			(end 0.12065 0.3048)
			(stroke
				(width 0.1)
				(type default)
			)
			(layer "B.Fab")
		)
		(fp_line
			(start -0.120396 0.2794)
			(end 0.12065 0.2794)
			(stroke
				(width 0.1)
				(type default)
			)
			(layer "B.Fab")
		)
		(fp_line
			(start 0.67945 0.3048)
			(end 0.67945 -0.305054)
			(stroke
				(width 0.1)
				(type default)
			)
			(layer "B.Fab")
		)
		(fp_line
			(start 0.12065 0.3048)
			(end 0.67945 0.3048)
			(stroke
				(width 0.1)
				(type default)
			)
			(layer "B.Fab")
		)
		(fp_line
			(start -0.120396 0.3048)
			(end -0.120396 0.2794)
			(stroke
				(width 0.1)
				(type default)
			)
			(layer "B.Fab")
		)
		(fp_line
			(start -0.67945 0.3048)
			(end -0.120396 0.3048)
			(stroke
				(width 0.1)
				(type default)
			)
			(layer "B.Fab")
		)
		(pad "1" smd circle
			(at 0.40005 0 270)
			(size 0 0)
			(layers "B.Cu" "B.Mask" "B.Paste")
			(net "PVDD18_S5_P1")
		)
		(pad "2" smd circle
			(at -0.40005 0 270)
			(size 0 0)
			(layers "B.Cu" "B.Mask" "B.Paste")
			(net "PVDD11_S3_P1_OCP_N_R")
		)
	)
	(footprint ""
		(layer "B.Cu")
		(at 179.7812 -133.111748 -90)
		(property "Reference" "R1422"
			(at 0 0 90)
			(layer "B.SilkS")
			(hide yes)
			(effects
				(font
					(size 1.27 1.27)
				)
				(justify mirror)
			)
		)
		(property "Value" ""
			(at 0 0 90)
			(layer "B.Fab")
			(effects
				(font
					(size 1.27 1.27)
				)
				(justify mirror)
			)
		)
		(duplicate_pad_numbers_are_jumpers no)
		(fp_line
			(start -0.7874 0.4064)
			(end 0.7874 0.4064)
			(stroke
				(width 0.1524)
				(type default)
			)
			(layer "B.SilkS")
		)
		(fp_line
			(start 0.7874 0.4064)
			(end 0.7874 -0.4064)
			(stroke
				(width 0.1524)
				(type default)
			)
			(layer "B.SilkS")
		)
		(fp_line
			(start -0.7874 -0.4064)
			(end -0.7874 0.4064)
			(stroke
				(width 0.1524)
				(type default)
			)
			(layer "B.SilkS")
		)
		(fp_line
			(start 0.7874 -0.4064)
			(end -0.7874 -0.4064)
			(stroke
				(width 0.1524)
				(type default)
			)
			(layer "B.SilkS")
		)
		(fp_line
			(start -0.67945 0.3048)
			(end -0.120396 0.3048)
			(stroke
				(width 0.1)
				(type default)
			)
			(layer "B.Fab")
		)
		(fp_line
			(start -0.120396 0.3048)
			(end -0.120396 0.2794)
			(stroke
				(width 0.1)
				(type default)
			)
			(layer "B.Fab")
		)
		(fp_line
			(start 0.12065 0.3048)
			(end 0.67945 0.3048)
			(stroke
				(width 0.1)
				(type default)
			)
			(layer "B.Fab")
		)
		(fp_line
			(start 0.67945 0.3048)
			(end 0.67945 -0.305054)
			(stroke
				(width 0.1)
				(type default)
			)
			(layer "B.Fab")
		)
		(fp_line
			(start -0.120396 0.2794)
			(end 0.12065 0.2794)
			(stroke
				(width 0.1)
				(type default)
			)
			(layer "B.Fab")
		)
		(fp_line
			(start 0.12065 0.2794)
			(end 0.12065 0.3048)
			(stroke
				(width 0.1)
				(type default)
			)
			(layer "B.Fab")
		)
		(fp_line
			(start -0.12065 -0.2794)
			(end -0.12065 -0.3048)
			(stroke
				(width 0.1)
				(type default)
			)
			(layer "B.Fab")
		)
		(fp_line
			(start 0.12065 -0.2794)
			(end -0.12065 -0.2794)
			(stroke
				(width 0.1)
				(type default)
			)
			(layer "B.Fab")
		)
		(fp_line
			(start -0.67945 -0.3048)
			(end -0.67945 0.3048)
			(stroke
				(width 0.1)
				(type default)
			)
			(layer "B.Fab")
		)
		(fp_line
			(start -0.12065 -0.3048)
			(end -0.67945 -0.3048)
			(stroke
				(width 0.1)
				(type default)
			)
			(layer "B.Fab")
		)
		(fp_line
			(start 0.12065 -0.305054)
			(end 0.12065 -0.2794)
			(stroke
				(width 0.1)
				(type default)
			)
			(layer "B.Fab")
		)
		(fp_line
			(start 0.67945 -0.305054)
			(end 0.12065 -0.305054)
			(stroke
				(width 0.1)
				(type default)
			)
			(layer "B.Fab")
		)
		(pad "1" smd circle
			(at 0.40005 0 90)
			(size 0 0)
			(layers "B.Cu" "B.Mask" "B.Paste")
			(net "PWRGD_CPU0_PWROK")
		)
		(pad "2" smd circle
			(at -0.40005 0 90)
			(size 0 0)
			(layers "B.Cu" "B.Mask" "B.Paste")
			(net "PWRGD_CPU1_PWROK")
		)
	)
	(footprint ""
		(layer "B.Cu")
		(at 138.7729 -9.03859 90)
		(property "Reference" "R6034"
			(at 0 0 90)
			(layer "B.SilkS")
			(hide yes)
			(effects
				(font
					(size 1.27 1.27)
				)
				(justify mirror)
			)
		)
		(property "Value" ""
			(at 0 0 90)
			(layer "B.Fab")
			(effects
				(font
					(size 1.27 1.27)
				)
				(justify mirror)
			)
		)
		(duplicate_pad_numbers_are_jumpers no)
		(fp_line
			(start 0.7874 -0.4064)
			(end -0.7874 -0.4064)
			(stroke
				(width 0.1524)
				(type default)
			)
			(layer "B.SilkS")
		)
		(fp_line
			(start -0.7874 -0.4064)
			(end -0.7874 0.4064)
			(stroke
				(width 0.1524)
				(type default)
			)
			(layer "B.SilkS")
		)
		(fp_line
			(start 0.7874 0.4064)
			(end 0.7874 -0.4064)
			(stroke
				(width 0.1524)
				(type default)
			)
			(layer "B.SilkS")
		)
		(fp_line
			(start -0.7874 0.4064)
			(end 0.7874 0.4064)
			(stroke
				(width 0.1524)
				(type default)
			)
			(layer "B.SilkS")
		)
		(fp_line
			(start 0.67945 -0.305054)
			(end 0.12065 -0.305054)
			(stroke
				(width 0.1)
				(type default)
			)
			(layer "B.Fab")
		)
		(fp_line
			(start 0.12065 -0.305054)
			(end 0.12065 -0.2794)
			(stroke
				(width 0.1)
				(type default)
			)
			(layer "B.Fab")
		)
		(fp_line
			(start -0.12065 -0.3048)
			(end -0.67945 -0.3048)
			(stroke
				(width 0.1)
				(type default)
			)
			(layer "B.Fab")
		)
		(fp_line
			(start -0.67945 -0.3048)
			(end -0.67945 0.3048)
			(stroke
				(width 0.1)
				(type default)
			)
			(layer "B.Fab")
		)
		(fp_line
			(start 0.12065 -0.2794)
			(end -0.12065 -0.2794)
			(stroke
				(width 0.1)
				(type default)
			)
			(layer "B.Fab")
		)
		(fp_line
			(start -0.12065 -0.2794)
			(end -0.12065 -0.3048)
			(stroke
				(width 0.1)
				(type default)
			)
			(layer "B.Fab")
		)
		(fp_line
			(start 0.12065 0.2794)
			(end 0.12065 0.3048)
			(stroke
				(width 0.1)
				(type default)
			)
			(layer "B.Fab")
		)
		(fp_line
			(start -0.120396 0.2794)
			(end 0.12065 0.2794)
			(stroke
				(width 0.1)
				(type default)
			)
			(layer "B.Fab")
		)
		(fp_line
			(start 0.67945 0.3048)
			(end 0.67945 -0.305054)
			(stroke
				(width 0.1)
				(type default)
			)
			(layer "B.Fab")
		)
		(fp_line
			(start 0.12065 0.3048)
			(end 0.67945 0.3048)
			(stroke
				(width 0.1)
				(type default)
			)
			(layer "B.Fab")
		)
		(fp_line
			(start -0.120396 0.3048)
			(end -0.120396 0.2794)
			(stroke
				(width 0.1)
				(type default)
			)
			(layer "B.Fab")
		)
		(fp_line
			(start -0.67945 0.3048)
			(end -0.120396 0.3048)
			(stroke
				(width 0.1)
				(type default)
			)
			(layer "B.Fab")
		)
		(pad "1" smd circle
			(at 0.40005 0 270)
			(size 0 0)
			(layers "B.Cu" "B.Mask" "B.Paste")
			(net "P3V3_AUX")
		)
		(pad "2" smd circle
			(at -0.40005 0 270)
			(size 0 0)
			(layers "B.Cu" "B.Mask" "B.Paste")
			(net "SCM_ROT_CPU_RST_R_N")
		)
	)
	(footprint ""
		(layer "B.Cu")
		(at 342.973406 -416.899344 90)
		(property "Reference" "C6557"
			(at 0 0 90)
			(layer "B.SilkS")
			(hide yes)
			(effects
				(font
					(size 1.27 1.27)
				)
				(justify mirror)
			)
		)
		(property "Value" ""
			(at 0 0 90)
			(layer "B.Fab")
			(effects
				(font
					(size 1.27 1.27)
				)
				(justify mirror)
			)
		)
		(duplicate_pad_numbers_are_jumpers no)
		(fp_line
			(start 0.299974 -0.150114)
			(end -0.299974 -0.150114)
			(stroke
				(width 0.1)
				(type default)
			)
			(layer "B.Fab")
		)
		(fp_line
			(start -0.299974 -0.150114)
			(end -0.299974 0.150114)
			(stroke
				(width 0.1)
				(type default)
			)
			(layer "B.Fab")
		)
		(fp_line
			(start 0.299974 0.150114)
			(end 0.299974 -0.150114)
			(stroke
				(width 0.1)
				(type default)
			)
			(layer "B.Fab")
		)
		(fp_line
			(start -0.299974 0.150114)
			(end 0.299974 0.150114)
			(stroke
				(width 0.1)
				(type default)
			)
			(layer "B.Fab")
		)
		(pad "1" smd rect
			(at 0.2667 0 270)
			(size 0.3048 0.381)
			(layers "B.Cu" "B.Mask" "B.Paste")
			(net "P5E_CPU0_P1_TX_BUF_C_DP<12>")
		)
		(pad "2" smd rect
			(at -0.2667 0 270)
			(size 0.3048 0.381)
			(layers "B.Cu" "B.Mask" "B.Paste")
			(net "P5E_CPU0_P1_TX_BUF_DP<12>")
		)
	)
	(footprint ""
		(layer "B.Cu")
		(at 239.903 -337.312)
		(property "Reference" "R1394"
			(at 0 0 0)
			(layer "B.SilkS")
			(hide yes)
			(effects
				(font
					(size 1.27 1.27)
				)
				(justify mirror)
			)
		)
		(property "Value" ""
			(at 0 0 0)
			(layer "B.Fab")
			(effects
				(font
					(size 1.27 1.27)
				)
				(justify mirror)
			)
		)
		(duplicate_pad_numbers_are_jumpers no)
		(fp_line
			(start -0.32512 -0.175006)
			(end -0.32512 0.175006)
			(stroke
				(width 0.1)
				(type default)
			)
			(layer "B.Fab")
		)
		(fp_line
			(start -0.32512 0.175006)
			(end 0.32512 0.175006)
			(stroke
				(width 0.1)
				(type default)
			)
			(layer "B.Fab")
		)
		(fp_line
			(start 0.32512 -0.175006)
			(end -0.32512 -0.175006)
			(stroke
				(width 0.1)
				(type default)
			)
			(layer "B.Fab")
		)
		(fp_line
			(start 0.32512 0.175006)
			(end 0.32512 -0.175006)
			(stroke
				(width 0.1)
				(type default)
			)
			(layer "B.Fab")
		)
		(pad "1" smd rect
			(at 0.2667 0 180)
			(size 0.3048 0.381)
			(layers "B.Cu" "B.Mask" "B.Paste")
			(net "P1V8_CPU1_RT_1D")
		)
		(pad "2" smd rect
			(at -0.2667 0)
			(size 0.3048 0.381)
			(layers "B.Cu" "B.Mask" "B.Paste")
			(net "SMB_RT_CPU1_P1_ROM_MUX_2D_R_SCL")
		)
	)
)
